(kicad_pcb
	(version 20260206)
	(generator "pcbnew")
	(generator_version "10.0")
	(general
		(thickness 1.6)
		(legacy_teardrops no)
	)
	(paper "A4")
	(title_block
		(title "fcb — 12433-1M.1206WZS1330.brd")
		(comment 1 "Open Vault / Knox (Wiwynn) / footprints 458-464 of 495")
	)
	(layers
		(0 "F.Cu" signal "TOP")
		(4 "In1.Cu" signal "L2GND")
		(6 "In2.Cu" signal "L3VCC")
		(2 "B.Cu" signal "BOTTOM")
		(9 "F.Adhes" user "F.Adhesive")
		(11 "B.Adhes" user "B.Adhesive")
		(13 "F.Paste" user "Package Geometry/Pastemask Top")
		(15 "B.Paste" user "Package Geometry/Pastemask Bottom")
		(5 "F.SilkS" user "Ref Des/Silkscreen Top")
		(7 "B.SilkS" user "Ref Des/Silkscreen Bottom")
		(1 "F.Mask" user "Board Geometry/Soldermask Top")
		(3 "B.Mask" user "Board Geometry/Soldermask Bottom")
		(17 "Dwgs.User" user "User.Drawings")
		(19 "Cmts.User" user "User.Comments")
		(21 "Eco1.User" user "User.Eco1")
		(23 "Eco2.User" user "User.Eco2")
		(25 "Edge.Cuts" user "Board Geometry/Outline")
		(27 "Margin" user)
		(31 "F.CrtYd" user "Package Geometry/Place Bound Top")
		(29 "B.CrtYd" user "Package Geometry/Place Bound Bottom")
		(35 "F.Fab" user "Ref Des/Assembly Top")
		(33 "B.Fab" user "Ref Des/Assembly Bottom")
	)
	(footprint ""
		(layer "F.Cu")
		(at 17.2466 -400.2024)
		(property "Reference" "PQ13"
			(at 0 0 0)
			(layer "F.SilkS")
			(hide yes)
			(effects
				(font
					(size 1.27 1.27)
				)
			)
		)
		(property "Value" "PH0925CL-GP"
			(at -4.2799 -0.4572 0)
			(unlocked yes)
			(layer "F.Fab")
			(hide yes)
			(effects
				(font
					(size 1.016 1.016)
					(thickness 0.1524)
				)
			)
		)
		(property "Device Type" "LFPAK-5PH48-U"
			(at -4.2799 -1.9812 0)
			(unlocked yes)
			(layer "F.Fab")
			(hide yes)
			(effects
				(font
					(size 1.016 1.016)
					(thickness 0.1524)
				)
			)
		)
		(duplicate_pad_numbers_are_jumpers no)
		(fp_line
			(start -2.7559 -6.5532)
			(end -2.7559 1.0668)
			(stroke
				(width 0.1524)
				(type default)
			)
			(layer "F.SilkS")
		)
		(fp_line
			(start -2.7559 1.0668)
			(end 2.7559 1.0668)
			(stroke
				(width 0.1524)
				(type default)
			)
			(layer "F.SilkS")
		)
		(fp_line
			(start -1.7272 1.1684)
			(end -2.1082 1.1684)
			(stroke
				(width 0.3302)
				(type default)
			)
			(layer "F.SilkS")
		)
		(fp_line
			(start 2.7559 -6.5532)
			(end -2.7559 -6.5532)
			(stroke
				(width 0.1524)
				(type default)
			)
			(layer "F.SilkS")
		)
		(fp_line
			(start 2.7559 1.0668)
			(end 2.7559 -6.5532)
			(stroke
				(width 0.1524)
				(type default)
			)
			(layer "F.SilkS")
		)
		(fp_poly
			(pts
				(xy -2.3368 1.5748) (xy -1.905 1.143) (xy -1.4732 1.5748)
			)
			(stroke
				(width 0)
				(type default)
			)
			(fill yes)
			(layer "F.SilkS")
		)
		(fp_poly
			(pts
				(xy -2.5019 -4.02971) (xy -0.3302 -4.02971) (xy -0.3302 -6.30301) (xy -2.5019 -6.30301)
			)
			(stroke
				(width 0)
				(type default)
			)
			(fill yes)
			(layer "F.Paste")
		)
		(fp_poly
			(pts
				(xy -2.5019 -1.09601) (xy -0.3302 -1.09601) (xy -0.3302 -3.36931) (xy -2.5019 -3.36931)
			)
			(stroke
				(width 0)
				(type default)
			)
			(fill yes)
			(layer "F.Paste")
		)
		(fp_poly
			(pts
				(xy 0.3302 -4.02971) (xy 2.5019 -4.02971) (xy 2.5019 -6.30301) (xy 0.3302 -6.30301)
			)
			(stroke
				(width 0)
				(type default)
			)
			(fill yes)
			(layer "F.Paste")
		)
		(fp_poly
			(pts
				(xy 0.3302 -1.09601) (xy 2.5019 -1.09601) (xy 2.5019 -3.36931) (xy 0.3302 -3.36931)
			)
			(stroke
				(width 0)
				(type default)
			)
			(fill yes)
			(layer "F.Paste")
		)
		(fp_rect
			(start -2.4511 0.3048)
			(end 2.4511 -5.6896)
			(stroke
				(width 0)
				(type default)
			)
			(fill no)
			(layer "F.CrtYd")
		)
		(fp_poly
			(pts
				(xy -3.0099 1.3208) (xy -3.0099 -6.8072) (xy 3.0099 -6.8072) (xy 3.0099 -1.016) (xy 2.4511 -1.016)
				(xy 2.4511 -5.6896) (xy -2.4511 -5.6896) (xy -2.4511 0.3048) (xy 2.4511 0.3048) (xy 2.4511 -1.0033)
				(xy 3.0099 -1.0033) (xy 3.0099 1.3208)
			)
			(stroke
				(width 0)
				(type default)
			)
			(fill no)
			(layer "F.CrtYd")
		)
		(fp_rect
			(start -3.0099 1.3208)
			(end 3.0099 -6.8072)
			(stroke
				(width 0)
				(type default)
			)
			(fill no)
			(layer "F.Fab")
		)
		(pad "1" smd rect
			(at -1.905 0)
			(size 0.762 1.6256)
			(layers "F.Cu" "F.Mask" "F.Paste")
			(net "P12V")
		)
		(pad "2" smd rect
			(at -0.635 0)
			(size 0.762 1.6256)
			(layers "F.Cu" "F.Mask" "F.Paste")
			(net "P12V")
		)
		(pad "3" smd rect
			(at 0.635 0)
			(size 0.762 1.6256)
			(layers "F.Cu" "F.Mask" "F.Paste")
			(net "P12V")
		)
		(pad "4" smd rect
			(at 1.905 0)
			(size 0.762 1.6256)
			(layers "F.Cu" "F.Mask" "F.Paste")
			(net "ADM1276_GATE_DRV0")
		)
		(pad "5" smd rect
			(at 0 -3.69951)
			(size 5.0038 5.207)
			(layers "F.Cu" "F.Mask" "F.Paste")
			(net "P12V_SENSE_TRACE")
		)
	)
	(footprint ""
		(layer "F.Cu")
		(at 7.8232 -81.6102 90)
		(property "Reference" "R29"
			(at 0 0 90)
			(layer "F.SilkS")
			(hide yes)
			(effects
				(font
					(size 1.27 1.27)
				)
			)
		)
		(property "Value" "33R2F-3-GP"
			(at 0.064008 -3.993896 90)
			(unlocked yes)
			(layer "F.Fab")
			(hide yes)
			(effects
				(font
					(size 1.016 1.016)
					(thickness 0.1524)
				)
			)
		)
		(property "Device Type" "R402H16"
			(at 0.064008 -5.517896 90)
			(unlocked yes)
			(layer "F.Fab")
			(hide yes)
			(effects
				(font
					(size 1.016 1.016)
					(thickness 0.1524)
				)
			)
		)
		(duplicate_pad_numbers_are_jumpers no)
		(fp_line
			(start 0.508 -0.9398)
			(end -0.508 -0.9398)
			(stroke
				(width 0.1524)
				(type default)
			)
			(layer "F.SilkS")
		)
		(fp_line
			(start -0.508 -0.9398)
			(end -0.508 0.9398)
			(stroke
				(width 0.1524)
				(type default)
			)
			(layer "F.SilkS")
		)
		(fp_rect
			(start -0.508 0.9398)
			(end 0.508 -0.9398)
			(stroke
				(width 0)
				(type default)
			)
			(fill no)
			(layer "F.CrtYd")
		)
		(fp_rect
			(start -0.508 0.9398)
			(end 0.508 -0.9398)
			(stroke
				(width 0)
				(type default)
			)
			(fill no)
			(layer "F.Fab")
		)
		(pad "1" smd custom
			(at 0 -0.4445 90)
			(size 0.1397 0.1397)
			(layers "F.Cu" "F.Mask" "F.Paste")
			(net "P3V3")
			(options
				(clearance outline)
				(anchor circle)
			)
			(primitives
				(gr_poly
					(pts
						(arc
							(start -0.1778 -0.2794)
							(mid -0.249642 -0.249642)
							(end -0.2794 -0.1778)
						)
						(arc
							(start -0.2794 0.1778)
							(mid -0.249642 0.249642)
							(end -0.1778 0.2794)
						)
						(arc
							(start 0.1778 0.2794)
							(mid 0.249642 0.249642)
							(end 0.2794 0.1778)
						)
						(arc
							(start 0.2794 -0.1778)
							(mid 0.249642 -0.249642)
							(end 0.1778 -0.2794)
						)
					)
					(width 0)
					(fill yes)
				)
			)
		)
		(pad "2" smd custom
			(at 0 0.4445 90)
			(size 0.1397 0.1397)
			(layers "F.Cu" "F.Mask" "F.Paste")
			(net "LED_DR_LED4_BLUE")
			(options
				(clearance outline)
				(anchor circle)
			)
			(primitives
				(gr_poly
					(pts
						(arc
							(start -0.1778 -0.2794)
							(mid -0.249642 -0.249642)
							(end -0.2794 -0.1778)
						)
						(arc
							(start -0.2794 0.1778)
							(mid -0.249642 0.249642)
							(end -0.1778 0.2794)
						)
						(arc
							(start 0.1778 0.2794)
							(mid 0.249642 0.249642)
							(end 0.2794 0.1778)
						)
						(arc
							(start 0.2794 -0.1778)
							(mid 0.249642 -0.249642)
							(end 0.1778 -0.2794)
						)
					)
					(width 0)
					(fill yes)
				)
			)
		)
	)
	(footprint ""
		(layer "F.Cu")
		(at 33.401 -362.7882 -90)
		(property "Reference" "PR39"
			(at 0 0 270)
			(layer "F.SilkS")
			(hide yes)
			(effects
				(font
					(size 1.27 1.27)
				)
			)
		)
		(property "Value" "5K1R2F-2-GP"
			(at 0.064008 -3.993896 270)
			(unlocked yes)
			(layer "F.Fab")
			(hide yes)
			(effects
				(font
					(size 1.016 1.016)
					(thickness 0.1524)
				)
			)
		)
		(property "Device Type" "R402H16"
			(at 0.064008 -5.517896 270)
			(unlocked yes)
			(layer "F.Fab")
			(hide yes)
			(effects
				(font
					(size 1.016 1.016)
					(thickness 0.1524)
				)
			)
		)
		(duplicate_pad_numbers_are_jumpers no)
		(fp_line
			(start -0.508 -0.9398)
			(end -0.508 0.9398)
			(stroke
				(width 0.1524)
				(type default)
			)
			(layer "F.SilkS")
		)
		(fp_line
			(start 0.508 -0.9398)
			(end -0.508 -0.9398)
			(stroke
				(width 0.1524)
				(type default)
			)
			(layer "F.SilkS")
		)
		(fp_rect
			(start -0.508 0.9398)
			(end 0.508 -0.9398)
			(stroke
				(width 0)
				(type default)
			)
			(fill no)
			(layer "F.CrtYd")
		)
		(fp_rect
			(start -0.508 0.9398)
			(end 0.508 -0.9398)
			(stroke
				(width 0)
				(type default)
			)
			(fill no)
			(layer "F.Fab")
		)
		(pad "1" smd custom
			(at 0 -0.4445 270)
			(size 0.1397 0.1397)
			(layers "F.Cu" "F.Mask" "F.Paste")
			(net "TEMP_ALM#_REVERSE_R")
			(options
				(clearance outline)
				(anchor circle)
			)
			(primitives
				(gr_poly
					(pts
						(arc
							(start -0.1778 -0.2794)
							(mid -0.249642 -0.249642)
							(end -0.2794 -0.1778)
						)
						(arc
							(start -0.2794 0.1778)
							(mid -0.249642 0.249642)
							(end -0.1778 0.2794)
						)
						(arc
							(start 0.1778 0.2794)
							(mid 0.249642 0.249642)
							(end 0.2794 0.1778)
						)
						(arc
							(start 0.2794 -0.1778)
							(mid 0.249642 -0.249642)
							(end 0.1778 -0.2794)
						)
					)
					(width 0)
					(fill yes)
				)
			)
		)
		(pad "2" smd custom
			(at 0 0.4445 270)
			(size 0.1397 0.1397)
			(layers "F.Cu" "F.Mask" "F.Paste")
			(net "GND")
			(options
				(clearance outline)
				(anchor circle)
			)
			(primitives
				(gr_poly
					(pts
						(arc
							(start -0.1778 -0.2794)
							(mid -0.249642 -0.249642)
							(end -0.2794 -0.1778)
						)
						(arc
							(start -0.2794 0.1778)
							(mid -0.249642 0.249642)
							(end -0.1778 0.2794)
						)
						(arc
							(start 0.1778 0.2794)
							(mid 0.249642 0.249642)
							(end 0.2794 0.1778)
						)
						(arc
							(start 0.2794 -0.1778)
							(mid 0.249642 -0.249642)
							(end 0.1778 -0.2794)
						)
					)
					(width 0)
					(fill yes)
				)
			)
		)
	)
	(footprint ""
		(layer "F.Cu")
		(at 38.692074 -363.062774 180)
		(property "Reference" "PR40"
			(at 0 0 180)
			(layer "F.SilkS")
			(hide yes)
			(effects
				(font
					(size 1.27 1.27)
				)
			)
		)
		(property "Value" "54K9R2F-L-GP"
			(at 0.064008 -3.993896 180)
			(unlocked yes)
			(layer "F.Fab")
			(hide yes)
			(effects
				(font
					(size 1.016 1.016)
					(thickness 0.1524)
				)
			)
		)
		(property "Device Type" "R402H16"
			(at 0.064008 -5.517896 180)
			(unlocked yes)
			(layer "F.Fab")
			(hide yes)
			(effects
				(font
					(size 1.016 1.016)
					(thickness 0.1524)
				)
			)
		)
		(duplicate_pad_numbers_are_jumpers no)
		(fp_line
			(start 0.508 -0.9398)
			(end -0.508 -0.9398)
			(stroke
				(width 0.1524)
				(type default)
			)
			(layer "F.SilkS")
		)
		(fp_line
			(start -0.508 -0.9398)
			(end -0.508 0.9398)
			(stroke
				(width 0.1524)
				(type default)
			)
			(layer "F.SilkS")
		)
		(fp_rect
			(start -0.508 0.9398)
			(end 0.508 -0.9398)
			(stroke
				(width 0)
				(type default)
			)
			(fill no)
			(layer "F.CrtYd")
		)
		(fp_rect
			(start -0.508 0.9398)
			(end 0.508 -0.9398)
			(stroke
				(width 0)
				(type default)
			)
			(fill no)
			(layer "F.Fab")
		)
		(pad "1" smd custom
			(at 0 -0.4445 180)
			(size 0.1397 0.1397)
			(layers "F.Cu" "F.Mask" "F.Paste")
			(net "P12V_AUX")
			(options
				(clearance outline)
				(anchor circle)
			)
			(primitives
				(gr_poly
					(pts
						(arc
							(start -0.1778 -0.2794)
							(mid -0.249642 -0.249642)
							(end -0.2794 -0.1778)
						)
						(arc
							(start -0.2794 0.1778)
							(mid -0.249642 0.249642)
							(end -0.1778 0.2794)
						)
						(arc
							(start 0.1778 0.2794)
							(mid 0.249642 0.249642)
							(end 0.2794 0.1778)
						)
						(arc
							(start 0.2794 -0.1778)
							(mid 0.249642 -0.249642)
							(end 0.1778 -0.2794)
						)
					)
					(width 0)
					(fill yes)
				)
			)
		)
		(pad "2" smd custom
			(at 0 0.4445 180)
			(size 0.1397 0.1397)
			(layers "F.Cu" "F.Mask" "F.Paste")
			(net "TEMP_ALM#_REVERSE")
			(options
				(clearance outline)
				(anchor circle)
			)
			(primitives
				(gr_poly
					(pts
						(arc
							(start -0.1778 -0.2794)
							(mid -0.249642 -0.249642)
							(end -0.2794 -0.1778)
						)
						(arc
							(start -0.2794 0.1778)
							(mid -0.249642 0.249642)
							(end -0.1778 0.2794)
						)
						(arc
							(start 0.1778 0.2794)
							(mid 0.249642 0.249642)
							(end 0.2794 0.1778)
						)
						(arc
							(start 0.2794 -0.1778)
							(mid 0.249642 -0.249642)
							(end 0.1778 -0.2794)
						)
					)
					(width 0)
					(fill yes)
				)
			)
		)
	)
	(footprint ""
		(layer "F.Cu")
		(at 10.0838 -278.384 -90)
		(property "Reference" "R117"
			(at 0 0 270)
			(layer "F.SilkS")
			(hide yes)
			(effects
				(font
					(size 1.27 1.27)
				)
			)
		)
		(property "Value" "2KR2F-3-GP"
			(at 0.064008 -3.993896 270)
			(unlocked yes)
			(layer "F.Fab")
			(hide yes)
			(effects
				(font
					(size 1.016 1.016)
					(thickness 0.1524)
				)
			)
		)
		(property "Device Type" "R402H16"
			(at 0.064008 -5.517896 270)
			(unlocked yes)
			(layer "F.Fab")
			(hide yes)
			(effects
				(font
					(size 1.016 1.016)
					(thickness 0.1524)
				)
			)
		)
		(duplicate_pad_numbers_are_jumpers no)
		(fp_line
			(start -0.508 -0.9398)
			(end -0.508 0.9398)
			(stroke
				(width 0.1524)
				(type default)
			)
			(layer "F.SilkS")
		)
		(fp_line
			(start 0.508 -0.9398)
			(end -0.508 -0.9398)
			(stroke
				(width 0.1524)
				(type default)
			)
			(layer "F.SilkS")
		)
		(fp_rect
			(start -0.508 0.9398)
			(end 0.508 -0.9398)
			(stroke
				(width 0)
				(type default)
			)
			(fill no)
			(layer "F.CrtYd")
		)
		(fp_rect
			(start -0.508 0.9398)
			(end 0.508 -0.9398)
			(stroke
				(width 0)
				(type default)
			)
			(fill no)
			(layer "F.Fab")
		)
		(pad "1" smd custom
			(at 0 -0.4445 270)
			(size 0.1397 0.1397)
			(layers "F.Cu" "F.Mask" "F.Paste")
			(net "LED_DR_LED2")
			(options
				(clearance outline)
				(anchor circle)
			)
			(primitives
				(gr_poly
					(pts
						(arc
							(start -0.1778 -0.2794)
							(mid -0.249642 -0.249642)
							(end -0.2794 -0.1778)
						)
						(arc
							(start -0.2794 0.1778)
							(mid -0.249642 0.249642)
							(end -0.1778 0.2794)
						)
						(arc
							(start 0.1778 0.2794)
							(mid 0.249642 0.249642)
							(end 0.2794 0.1778)
						)
						(arc
							(start 0.2794 -0.1778)
							(mid 0.249642 -0.249642)
							(end 0.1778 -0.2794)
						)
					)
					(width 0)
					(fill yes)
				)
			)
		)
		(pad "2" smd custom
			(at 0 0.4445 270)
			(size 0.1397 0.1397)
			(layers "F.Cu" "F.Mask" "F.Paste")
			(net "LED_DR_LED2_B")
			(options
				(clearance outline)
				(anchor circle)
			)
			(primitives
				(gr_poly
					(pts
						(arc
							(start -0.1778 -0.2794)
							(mid -0.249642 -0.249642)
							(end -0.2794 -0.1778)
						)
						(arc
							(start -0.2794 0.1778)
							(mid -0.249642 0.249642)
							(end -0.1778 0.2794)
						)
						(arc
							(start 0.1778 0.2794)
							(mid 0.249642 0.249642)
							(end 0.2794 0.1778)
						)
						(arc
							(start 0.2794 -0.1778)
							(mid 0.249642 -0.249642)
							(end 0.1778 -0.2794)
						)
					)
					(width 0)
					(fill yes)
				)
			)
		)
	)
	(footprint ""
		(layer "F.Cu")
		(at 39.116 -252.603 -90)
		(property "Reference" "TP19"
			(at 0 0 270)
			(layer "F.SilkS")
			(hide yes)
			(effects
				(font
					(size 1.27 1.27)
				)
			)
		)
		(property "Value" "TPAD32-GP"
			(at 0 -3.166364 270)
			(unlocked yes)
			(layer "F.Fab")
			(hide yes)
			(effects
				(font
					(size 1.016 1.016)
					(thickness 0.1524)
				)
			)
		)
		(property "Device Type" "TPAD32"
			(at 0 -4.690618 270)
			(unlocked yes)
			(layer "F.Fab")
			(hide yes)
			(effects
				(font
					(size 1.016 1.016)
					(thickness 0.1524)
				)
			)
		)
		(duplicate_pad_numbers_are_jumpers no)
		(fp_poly
			(pts
				(arc
					(start 0.7112 0)
					(mid -0.7112 0)
					(end 0.7112 0)
				)
			)
			(stroke
				(width 0)
				(type default)
			)
			(fill no)
			(layer "F.CrtYd")
		)
		(fp_poly
			(pts
				(arc
					(start 0.7112 0)
					(mid -0.7112 0)
					(end 0.7112 0)
				)
			)
			(stroke
				(width 0)
				(type default)
			)
			(fill no)
			(layer "F.Fab")
		)
		(pad "1" smd circle
			(at 0 0 270)
			(size 0.8128 0.8128)
			(layers "F.Cu" "F.Mask" "F.Paste")
			(net "LED_DR_LED6_RESERVE")
		)
	)
	(footprint ""
		(layer "F.Cu")
		(at 5.5626 -429.9712 90)
		(property "Reference" "R31"
			(at 0 0 90)
			(layer "F.SilkS")
			(hide yes)
			(effects
				(font
					(size 1.27 1.27)
				)
			)
		)
		(property "Value" "33R2F-3-GP"
			(at 0.064008 -3.993896 90)
			(unlocked yes)
			(layer "F.Fab")
			(hide yes)
			(effects
				(font
					(size 1.016 1.016)
					(thickness 0.1524)
				)
			)
		)
		(property "Device Type" "R402H16"
			(at 0.064008 -5.517896 90)
			(unlocked yes)
			(layer "F.Fab")
			(hide yes)
			(effects
				(font
					(size 1.016 1.016)
					(thickness 0.1524)
				)
			)
		)
		(duplicate_pad_numbers_are_jumpers no)
		(fp_line
			(start 0.508 -0.9398)
			(end -0.508 -0.9398)
			(stroke
				(width 0.1524)
				(type default)
			)
			(layer "F.SilkS")
		)
		(fp_line
			(start -0.508 -0.9398)
			(end -0.508 0.9398)
			(stroke
				(width 0.1524)
				(type default)
			)
			(layer "F.SilkS")
		)
		(fp_rect
			(start -0.508 0.9398)
			(end 0.508 -0.9398)
			(stroke
				(width 0)
				(type default)
			)
			(fill no)
			(layer "F.CrtYd")
		)
		(fp_rect
			(start -0.508 0.9398)
			(end 0.508 -0.9398)
			(stroke
				(width 0)
				(type default)
			)
			(fill no)
			(layer "F.Fab")
		)
		(pad "1" smd custom
			(at 0 -0.4445 90)
			(size 0.1397 0.1397)
			(layers "F.Cu" "F.Mask" "F.Paste")
			(net "P3V3")
			(options
				(clearance outline)
				(anchor circle)
			)
			(primitives
				(gr_poly
					(pts
						(arc
							(start -0.1778 -0.2794)
							(mid -0.249642 -0.249642)
							(end -0.2794 -0.1778)
						)
						(arc
							(start -0.2794 0.1778)
							(mid -0.249642 0.249642)
							(end -0.1778 0.2794)
						)
						(arc
							(start 0.1778 0.2794)
							(mid 0.249642 0.249642)
							(end 0.2794 0.1778)
						)
						(arc
							(start 0.2794 -0.1778)
							(mid 0.249642 -0.249642)
							(end 0.1778 -0.2794)
						)
					)
					(width 0)
					(fill yes)
				)
			)
		)
		(pad "2" smd custom
			(at 0 0.4445 90)
			(size 0.1397 0.1397)
			(layers "F.Cu" "F.Mask" "F.Paste")
			(net "LED_DR_LED0_BLUE")
			(options
				(clearance outline)
				(anchor circle)
			)
			(primitives
				(gr_poly
					(pts
						(arc
							(start -0.1778 -0.2794)
							(mid -0.249642 -0.249642)
							(end -0.2794 -0.1778)
						)
						(arc
							(start -0.2794 0.1778)
							(mid -0.249642 0.249642)
							(end -0.1778 0.2794)
						)
						(arc
							(start 0.1778 0.2794)
							(mid 0.249642 0.249642)
							(end 0.2794 0.1778)
						)
						(arc
							(start 0.2794 -0.1778)
							(mid 0.249642 -0.249642)
							(end 0.1778 -0.2794)
						)
					)
					(width 0)
					(fill yes)
				)
			)
		)
	)
)
